FILE_TYPE = CONNECTIVITY;
{Allegro Design Entry HDL 17.2-2016 S081 (4005846) 1/11/2022}
"PAGE_NUMBER" = 63;
0"NC";
1"P5E_CPU0_P1_TX_C_DN<15:0>";
2"P5E_CPU0_P0_TX_DP<15:0>";
3"P5E_CPU0_P0_TX_DN<15:0>";
4"P5E_CPU0_P1_TX_C_DP<15:0>";
5"P5E_CPU0_P1_TX_DP<15:0>";
6"P5E_CPU0_P1_TX_DN<15:0>";
7"P5E_CPU0_P0_TX_C_DP<15:0>";
8"P5E_CPU0_P0_TX_C_DN<15:0>";
9"P5E_CPU0_P0_TX_DN<5>";
10"P5E_CPU0_P0_TX_DP<5>";
11"P5E_CPU0_P0_TX_C_DP<4>";
12"P5E_CPU0_P0_TX_C_DN<4>";
13"P5E_CPU0_P0_TX_DP<6>";
14"P5E_CPU0_P0_TX_DN<6>";
15"P5E_CPU0_P0_TX_DN<7>";
16"P5E_CPU0_P0_TX_DP<8>";
17"P5E_CPU0_P0_TX_DN<8>";
18"P5E_CPU0_P0_TX_DN<1>";
19"P5E_CPU0_P0_TX_DP<2>";
20"P5E_CPU0_P0_TX_DP<4>";
21"P5E_CPU0_P0_TX_DN<4>";
22"P5E_CPU0_P0_TX_C_DN<7>";
23"P5E_CPU0_P0_TX_C_DN<6>";
24"P5E_CPU0_P0_TX_C_DN<5>";
25"P5E_CPU0_P0_TX_C_DN<15>";
26"P5E_CPU0_P0_TX_C_DP<15>";
27"P5E_CPU0_P0_TX_C_DN<14>";
28"P5E_CPU0_P0_TX_C_DP<14>";
29"P5E_CPU0_P0_TX_C_DN<13>";
30"P5E_CPU0_P0_TX_C_DP<13>";
31"P5E_CPU0_P0_TX_C_DN<12>";
32"P5E_CPU0_P0_TX_C_DP<12>";
33"P5E_CPU0_P0_TX_C_DN<11>";
34"P5E_CPU0_P0_TX_C_DP<11>";
35"P5E_CPU0_P0_TX_C_DN<10>";
36"P5E_CPU0_P0_TX_C_DP<10>";
37"P5E_CPU0_P0_TX_C_DN<9>";
38"P5E_CPU0_P0_TX_C_DP<9>";
39"P5E_CPU0_P0_TX_C_DN<8>";
40"P5E_CPU0_P0_TX_C_DP<8>";
41"P5E_CPU0_P0_TX_C_DP<7>";
42"P5E_CPU0_P0_TX_C_DP<6>";
43"P5E_CPU0_P0_TX_C_DN<3>";
44"P5E_CPU0_P0_TX_C_DP<3>";
45"P5E_CPU0_P0_TX_C_DN<2>";
46"P5E_CPU0_P0_TX_C_DP<2>";
47"P5E_CPU0_P0_TX_C_DN<1>";
48"P5E_CPU0_P0_TX_C_DP<1>";
49"P5E_CPU0_P1_TX_DN<14>";
50"P5E_CPU0_P1_TX_DP<15>";
51"P5E_CPU0_P1_TX_DN<15>";
52"P5E_CPU0_P1_TX_DP<14>";
53"P5E_CPU0_P1_TX_DN<11>";
54"P5E_CPU0_P1_TX_DN<13>";
55"P5E_CPU0_P1_TX_DP<13>";
56"P5E_CPU0_P1_TX_DN<12>";
57"P5E_CPU0_P1_TX_C_DP<15>";
58"P5E_CPU0_P1_TX_C_DP<13>";
59"P5E_CPU0_P1_TX_C_DN<12>";
60"P5E_CPU0_P1_TX_DP<12>";
61"P5E_CPU0_P1_TX_DP<11>";
62"P5E_CPU0_P1_TX_DN<10>";
63"P5E_CPU0_P1_TX_DP<10>";
64"P5E_CPU0_P1_TX_DN<9>";
65"P5E_CPU0_P1_TX_C_DN<13>";
66"P5E_CPU0_P1_TX_C_DP<14>";
67"P5E_CPU0_P1_TX_C_DN<14>";
68"P5E_CPU0_P1_TX_C_DP<12>";
69"P5E_CPU0_P1_TX_C_DN<11>";
70"P5E_CPU0_P1_TX_C_DP<11>";
71"P5E_CPU0_P1_TX_C_DN<10>";
72"P5E_CPU0_P1_TX_C_DP<10>";
73"P5E_CPU0_P1_TX_C_DN<9>";
74"P5E_CPU0_P1_TX_C_DP<9>";
75"P5E_CPU0_P1_TX_DN<8>";
76"P5E_CPU0_P1_TX_DP<8>";
77"P5E_CPU0_P1_TX_DN<7>";
78"P5E_CPU0_P1_TX_DP<9>";
79"P5E_CPU0_P1_TX_DP<7>";
80"P5E_CPU0_P1_TX_C_DN<7>";
81"P5E_CPU0_P1_TX_DN<4>";
82"P5E_CPU0_P1_TX_DP<4>";
83"P5E_CPU0_P1_TX_DN<3>";
84"P5E_CPU0_P1_TX_DP<3>";
85"P5E_CPU0_P1_TX_DP<6>";
86"P5E_CPU0_P1_TX_DN<2>";
87"P5E_CPU0_P1_TX_DN<1>";
88"P5E_CPU0_P1_TX_DP<5>";
89"P5E_CPU0_P1_TX_DN<6>";
90"P5E_CPU0_P1_TX_DN<5>";
91"P5E_CPU0_P1_TX_DP<2>";
92"P5E_CPU0_P1_TX_DP<1>";
93"P5E_CPU0_P1_TX_DN<0>";
94"P5E_CPU0_P1_TX_C_DP<0>";
95"P5E_CPU0_P1_TX_C_DP<4>";
96"P5E_CPU0_P1_TX_C_DN<3>";
97"P5E_CPU0_P1_TX_C_DP<3>";
98"P5E_CPU0_P1_TX_C_DN<2>";
99"P5E_CPU0_P1_TX_C_DN<1>";
100"P5E_CPU0_P1_TX_C_DP<1>";
101"P5E_CPU0_P1_TX_C_DP<5>";
102"P5E_CPU0_P1_TX_C_DN<5>";
103"P5E_CPU0_P1_TX_C_DP<6>";
104"P5E_CPU0_P1_TX_C_DN<6>";
105"P5E_CPU0_P1_TX_C_DP<7>";
106"P5E_CPU0_P1_TX_C_DP<8>";
107"P5E_CPU0_P1_TX_C_DN<8>";
108"P5E_CPU0_P1_TX_C_DP<2>";
109"P5E_CPU0_P1_TX_C_DN<0>";
110"P5E_CPU0_P1_TX_DP<0>";
111"P5E_CPU0_P0_TX_DP<3>";
112"P5E_CPU0_P0_TX_DN<2>";
113"P5E_CPU0_P0_TX_DN<13>";
114"P5E_CPU0_P0_TX_DP<15>";
115"P5E_CPU0_P0_TX_DN<15>";
116"P5E_CPU0_P0_TX_DN<14>";
117"P5E_CPU0_P0_TX_DP<14>";
118"P5E_CPU0_P0_TX_DN<11>";
119"P5E_CPU0_P0_TX_DP<12>";
120"P5E_CPU0_P0_TX_DN<12>";
121"P5E_CPU0_P0_TX_DN<9>";
122"P5E_CPU0_P0_TX_DP<10>";
123"P5E_CPU0_P0_TX_DN<10>";
124"P5E_CPU0_P0_TX_DP<13>";
125"P5E_CPU0_P0_TX_DP<11>";
126"P5E_CPU0_P0_TX_DP<9>";
127"P5E_CPU0_P0_TX_DP<7>";
128"P5E_CPU0_P0_TX_C_DP<5>";
129"P5E_CPU0_P0_TX_C_DN<0>";
130"P5E_CPU0_P0_TX_C_DP<0>";
131"P5E_CPU0_P0_TX_DN<3>";
132"P5E_CPU0_P0_TX_DP<1>";
133"P5E_CPU0_P0_TX_DN<0>";
134"P5E_CPU0_P1_TX_C_DN<4>";
135"P5E_CPU0_P0_TX_DP<0>";
136"P5E_CPU0_P1_TX_C_DN<15>";
%"TAP"
"6","(-5650,4600)","0","standard","I10";
;
CDS_LIB"standard"
BODY_TYPE"PLUMBING"
HDL_TAP"TRUE";
"B \NAC \NWC"2;
"S \NAC"
BN"12"119;
%"TAP"
"6","(-3775,3150)","2","standard","I103";
;
BOM_COST"IO_SLOT"
BODY_TYPE"PLUMBING"
HDL_TAP"TRUE"
ROOM"RISER1"
CDS_LIB"standard";
"B \NAC \NWC"1;
"S \NAC"
BN"1"99;
%"TAP"
"6","(-3775,3250)","2","standard","I104";
;
BOM_COST"IO_SLOT"
BODY_TYPE"PLUMBING"
HDL_TAP"TRUE"
ROOM"RISER1"
CDS_LIB"standard";
"B \NAC \NWC"1;
"S \NAC"
BN"0"109;
%"TAP"
"6","(-3925,3200)","2","standard","I105";
;
BOM_COST"IO_SLOT"
BODY_TYPE"PLUMBING"
HDL_TAP"TRUE"
ROOM"RISER1"
CDS_LIB"standard";
"B \NAC \NWC"4;
"S \NAC"
BN"1"100;
%"TAP"
"6","(-3925,3300)","2","standard","I106";
;
BOM_COST"IO_SLOT"
BODY_TYPE"PLUMBING"
HDL_TAP"TRUE"
ROOM"RISER1"
CDS_LIB"standard";
"B \NAC \NWC"4;
"S \NAC"
BN"0"94;
%"TAP"
"6","(-3775,3050)","2","standard","I107";
;
BOM_COST"IO_SLOT"
BODY_TYPE"PLUMBING"
HDL_TAP"TRUE"
ROOM"RISER1"
CDS_LIB"standard";
"B \NAC \NWC"1;
"S \NAC"
BN"2"98;
%"TAP"
"6","(-3775,2950)","2","standard","I108";
;
BOM_COST"IO_SLOT"
BODY_TYPE"PLUMBING"
HDL_TAP"TRUE"
ROOM"RISER1"
CDS_LIB"standard";
"B \NAC \NWC"1;
"S \NAC"
BN"3"96;
%"TAP"
"6","(-3775,2850)","2","standard","I109";
;
BOM_COST"IO_SLOT"
BODY_TYPE"PLUMBING"
HDL_TAP"TRUE"
ROOM"RISER1"
CDS_LIB"standard";
"B \NAC \NWC"1;
"S \NAC"
BN"4"134;
%"TAP"
"6","(-5800,4750)","0","standard","I11";
;
CDS_LIB"standard"
BODY_TYPE"PLUMBING"
HDL_TAP"TRUE";
"B \NAC \NWC"3;
"S \NAC"
BN"10"123;
%"TAP"
"6","(-3775,2750)","2","standard","I110";
;
BOM_COST"IO_SLOT"
BODY_TYPE"PLUMBING"
HDL_TAP"TRUE"
ROOM"RISER1"
CDS_LIB"standard";
"B \NAC \NWC"1;
"S \NAC"
BN"5"102;
%"TAP"
"6","(-3775,2650)","2","standard","I111";
;
BOM_COST"IO_SLOT"
BODY_TYPE"PLUMBING"
HDL_TAP"TRUE"
ROOM"RISER1"
CDS_LIB"standard";
"B \NAC \NWC"1;
"S \NAC"
BN"6"104;
%"TAP"
"6","(-3925,3000)","2","standard","I112";
;
BOM_COST"IO_SLOT"
BODY_TYPE"PLUMBING"
HDL_TAP"TRUE"
ROOM"RISER1"
CDS_LIB"standard";
"B \NAC \NWC"4;
"S \NAC"
BN"3"97;
%"TAP"
"6","(-3925,3100)","2","standard","I113";
;
BOM_COST"IO_SLOT"
BODY_TYPE"PLUMBING"
HDL_TAP"TRUE"
ROOM"RISER1"
CDS_LIB"standard";
"B \NAC \NWC"4;
"S \NAC"
BN"2"108;
%"TAP"
"6","(-3925,2900)","2","standard","I114";
;
BOM_COST"IO_SLOT"
BODY_TYPE"PLUMBING"
HDL_TAP"TRUE"
ROOM"RISER1"
CDS_LIB"standard";
"B \NAC \NWC"4;
"S \NAC"
BN"4"95;
%"TAP"
"6","(-3925,2800)","2","standard","I115";
;
BOM_COST"IO_SLOT"
BODY_TYPE"PLUMBING"
HDL_TAP"TRUE"
ROOM"RISER1"
CDS_LIB"standard";
"B \NAC \NWC"4;
"S \NAC"
BN"5"101;
%"TAP"
"6","(-3925,2700)","2","standard","I116";
;
BOM_COST"IO_SLOT"
BODY_TYPE"PLUMBING"
HDL_TAP"TRUE"
ROOM"RISER1"
CDS_LIB"standard";
"B \NAC \NWC"4;
"S \NAC"
BN"6"103;
%"TAP"
"6","(-3775,2550)","2","standard","I117";
;
BOM_COST"IO_SLOT"
BODY_TYPE"PLUMBING"
HDL_TAP"TRUE"
ROOM"RISER1"
CDS_LIB"standard";
"B \NAC \NWC"1;
"S \NAC"
BN"7"80;
%"TAP"
"6","(-3775,2450)","2","standard","I118";
;
BOM_COST"IO_SLOT"
BODY_TYPE"PLUMBING"
HDL_TAP"TRUE"
ROOM"RISER1"
CDS_LIB"standard";
"B \NAC \NWC"1;
"S \NAC"
BN"8"107;
%"TAP"
"6","(-3775,2350)","2","standard","I119";
;
BOM_COST"IO_SLOT"
BODY_TYPE"PLUMBING"
HDL_TAP"TRUE"
ROOM"RISER1"
CDS_LIB"standard";
"B \NAC \NWC"1;
"S \NAC"
BN"9"73;
%"TAP"
"6","(-5800,4850)","0","standard","I12";
;
CDS_LIB"standard"
BODY_TYPE"PLUMBING"
HDL_TAP"TRUE";
"B \NAC \NWC"3;
"S \NAC"
BN"9"121;
%"TAP"
"6","(-3775,2250)","2","standard","I120";
;
BOM_COST"IO_SLOT"
BODY_TYPE"PLUMBING"
HDL_TAP"TRUE"
ROOM"RISER1"
CDS_LIB"standard";
"B \NAC \NWC"1;
"S \NAC"
BN"10"71;
%"TAP"
"6","(-3775,2150)","2","standard","I121";
;
BOM_COST"IO_SLOT"
BODY_TYPE"PLUMBING"
HDL_TAP"TRUE"
ROOM"RISER1"
CDS_LIB"standard";
"B \NAC \NWC"1;
"S \NAC"
BN"11"69;
%"TAP"
"6","(-3925,2400)","2","standard","I122";
;
BOM_COST"IO_SLOT"
BODY_TYPE"PLUMBING"
HDL_TAP"TRUE"
ROOM"RISER1"
CDS_LIB"standard";
"B \NAC \NWC"4;
"S \NAC"
BN"9"74;
%"TAP"
"6","(-3925,2500)","2","standard","I123";
;
BOM_COST"IO_SLOT"
BODY_TYPE"PLUMBING"
HDL_TAP"TRUE"
ROOM"RISER1"
CDS_LIB"standard";
"B \NAC \NWC"4;
"S \NAC"
BN"8"106;
%"TAP"
"6","(-3925,2600)","2","standard","I124";
;
BOM_COST"IO_SLOT"
BODY_TYPE"PLUMBING"
HDL_TAP"TRUE"
ROOM"RISER1"
CDS_LIB"standard";
"B \NAC \NWC"4;
"S \NAC"
BN"7"105;
%"TAP"
"6","(-3925,2300)","2","standard","I125";
;
BOM_COST"IO_SLOT"
BODY_TYPE"PLUMBING"
HDL_TAP"TRUE"
ROOM"RISER1"
CDS_LIB"standard";
"B \NAC \NWC"4;
"S \NAC"
BN"10"72;
%"TAP"
"6","(-3925,2200)","2","standard","I126";
;
BOM_COST"IO_SLOT"
BODY_TYPE"PLUMBING"
HDL_TAP"TRUE"
ROOM"RISER1"
CDS_LIB"standard";
"B \NAC \NWC"4;
"S \NAC"
BN"11"70;
%"TAP"
"6","(-3775,2050)","2","standard","I127";
;
BOM_COST"IO_SLOT"
BODY_TYPE"PLUMBING"
HDL_TAP"TRUE"
ROOM"RISER1"
CDS_LIB"standard";
"B \NAC \NWC"1;
"S \NAC"
BN"12"59;
%"TAP"
"6","(-3775,1950)","2","standard","I128";
;
BOM_COST"IO_SLOT"
BODY_TYPE"PLUMBING"
HDL_TAP"TRUE"
ROOM"RISER1"
CDS_LIB"standard";
"B \NAC \NWC"1;
"S \NAC"
BN"13"65;
%"TAP"
"6","(-3775,1850)","2","standard","I129";
;
BOM_COST"IO_SLOT"
BODY_TYPE"PLUMBING"
HDL_TAP"TRUE"
ROOM"RISER1"
CDS_LIB"standard";
"B \NAC \NWC"1;
"S \NAC"
BN"14"67;
%"TAP"
"6","(-5800,4950)","0","standard","I13";
;
CDS_LIB"standard"
BODY_TYPE"PLUMBING"
HDL_TAP"TRUE";
"B \NAC \NWC"3;
"S \NAC"
BN"8"17;
%"TAP"
"6","(-3775,1750)","2","standard","I130";
;
BOM_COST"IO_SLOT"
BODY_TYPE"PLUMBING"
HDL_TAP"TRUE"
ROOM"RISER1"
CDS_LIB"standard";
"B \NAC \NWC"1;
"S \NAC"
BN"15"136;
%"TAP"
"6","(-3925,1900)","2","standard","I131";
;
BOM_COST"IO_SLOT"
BODY_TYPE"PLUMBING"
HDL_TAP"TRUE"
ROOM"RISER1"
CDS_LIB"standard";
"B \NAC \NWC"4;
"S \NAC"
BN"14"66;
%"TAP"
"6","(-3925,2000)","2","standard","I132";
;
BOM_COST"IO_SLOT"
BODY_TYPE"PLUMBING"
HDL_TAP"TRUE"
ROOM"RISER1"
CDS_LIB"standard";
"B \NAC \NWC"4;
"S \NAC"
BN"13"58;
%"TAP"
"6","(-3925,2100)","2","standard","I133";
;
BOM_COST"IO_SLOT"
BODY_TYPE"PLUMBING"
HDL_TAP"TRUE"
ROOM"RISER1"
CDS_LIB"standard";
"B \NAC \NWC"4;
"S \NAC"
BN"12"68;
%"TAP"
"6","(-3925,1800)","2","standard","I134";
;
BOM_COST"IO_SLOT"
BODY_TYPE"PLUMBING"
HDL_TAP"TRUE"
ROOM"RISER1"
CDS_LIB"standard";
"B \NAC \NWC"4;
"S \NAC"
BN"15"57;
%"Q_CAP_DIFFBUS"
"2","(-4925,3300)","0","pure_quanta","I135";
;
LOCATION"C554"
$SEC"1"
CDS_SEC"1"
PACK_TYPE"C0201"
MATERIAL"X6S"
TOLERANCE"20%"
PART_NUMBER"SP_CH4221MEE01"
VOLTAGE"6.3V"
VALUE"DIFF BUS_0.22UF"
PIN_NAMES_ROTATE"True"
CDS_LMAN_SYM_OUTLINE"-25,50,25,-50"
CDS_LIB"pure_quanta";
"2"
$PN"2"94;
"1"
$PN"1"110;
%"Q_CAP_DIFFBUS"
"2","(-4925,3250)","2","pure_quanta","I136";
;
LOCATION"C555"
$SEC"1"
CDS_SEC"1"
VALUE"DIFF BUS_0.22UF"
VOLTAGE"6.3V"
TOLERANCE"20%"
PART_NUMBER"SP_CH4221MEE01"
MATERIAL"X6S"
PIN_NAMES_ROTATE"True"
PACK_TYPE"C0201"
CDS_LMAN_SYM_OUTLINE"-25,50,25,-50"
CDS_LIB"pure_quanta";
"2"
$PN"2"93;
"1"
$PN"1"109;
%"Q_CAP_DIFFBUS"
"2","(-4925,3200)","2","pure_quanta","I137";
;
LOCATION"C556"
$SEC"1"
CDS_SEC"1"
VALUE"DIFF BUS_0.22UF"
VOLTAGE"6.3V"
TOLERANCE"20%"
PART_NUMBER"SP_CH4221MEE01"
MATERIAL"X6S"
PIN_NAMES_ROTATE"True"
PACK_TYPE"C0201"
CDS_LMAN_SYM_OUTLINE"-25,50,25,-50"
CDS_LIB"pure_quanta";
"2"
$PN"2"92;
"1"
$PN"1"100;
%"Q_CAP_DIFFBUS"
"2","(-4925,3150)","2","pure_quanta","I138";
;
LOCATION"C557"
$SEC"1"
CDS_SEC"1"
VALUE"DIFF BUS_0.22UF"
VOLTAGE"6.3V"
TOLERANCE"20%"
PART_NUMBER"SP_CH4221MEE01"
MATERIAL"X6S"
PIN_NAMES_ROTATE"True"
PACK_TYPE"C0201"
CDS_LMAN_SYM_OUTLINE"-25,50,25,-50"
CDS_LIB"pure_quanta";
"2"
$PN"2"87;
"1"
$PN"1"99;
%"Q_CAP_DIFFBUS"
"2","(-4925,3100)","2","pure_quanta","I139";
;
LOCATION"C558"
$SEC"1"
CDS_SEC"1"
VALUE"DIFF BUS_0.22UF"
PACK_TYPE"C0201"
PIN_NAMES_ROTATE"True"
MATERIAL"X6S"
PART_NUMBER"SP_CH4221MEE01"
TOLERANCE"20%"
VOLTAGE"6.3V"
CDS_LMAN_SYM_OUTLINE"-25,50,25,-50"
CDS_LIB"pure_quanta";
"2"
$PN"2"91;
"1"
$PN"1"108;
%"TAP"
"6","(-5800,5050)","0","standard","I14";
;
CDS_LIB"standard"
BODY_TYPE"PLUMBING"
HDL_TAP"TRUE";
"B \NAC \NWC"3;
"S \NAC"
BN"7"15;
%"Q_CAP_DIFFBUS"
"2","(-4925,3050)","2","pure_quanta","I140";
;
LOCATION"C559"
$SEC"1"
CDS_SEC"1"
VALUE"DIFF BUS_0.22UF"
VOLTAGE"6.3V"
TOLERANCE"20%"
PART_NUMBER"SP_CH4221MEE01"
MATERIAL"X6S"
PIN_NAMES_ROTATE"True"
PACK_TYPE"C0201"
CDS_LMAN_SYM_OUTLINE"-25,50,25,-50"
CDS_LIB"pure_quanta";
"2"
$PN"2"86;
"1"
$PN"1"98;
%"Q_CAP_DIFFBUS"
"2","(-4925,3000)","2","pure_quanta","I141";
;
LOCATION"C560"
$SEC"1"
CDS_SEC"1"
VALUE"DIFF BUS_0.22UF"
VOLTAGE"6.3V"
TOLERANCE"20%"
PART_NUMBER"SP_CH4221MEE01"
MATERIAL"X6S"
PIN_NAMES_ROTATE"True"
PACK_TYPE"C0201"
CDS_LMAN_SYM_OUTLINE"-25,50,25,-50"
CDS_LIB"pure_quanta";
"2"
$PN"2"84;
"1"
$PN"1"97;
%"Q_CAP_DIFFBUS"
"2","(-4925,2950)","2","pure_quanta","I142";
;
LOCATION"C561"
$SEC"1"
CDS_SEC"1"
VALUE"DIFF BUS_0.22UF"
VOLTAGE"6.3V"
TOLERANCE"20%"
PART_NUMBER"SP_CH4221MEE01"
MATERIAL"X6S"
PIN_NAMES_ROTATE"True"
PACK_TYPE"C0201"
CDS_LMAN_SYM_OUTLINE"-25,50,25,-50"
CDS_LIB"pure_quanta";
"2"
$PN"2"83;
"1"
$PN"1"96;
%"Q_CAP_DIFFBUS"
"2","(-4925,2900)","2","pure_quanta","I143";
;
LOCATION"C562"
$SEC"1"
CDS_SEC"1"
VALUE"DIFF BUS_0.22UF"
PACK_TYPE"C0201"
PIN_NAMES_ROTATE"True"
MATERIAL"X6S"
PART_NUMBER"SP_CH4221MEE01"
TOLERANCE"20%"
VOLTAGE"6.3V"
CDS_LMAN_SYM_OUTLINE"-25,50,25,-50"
CDS_LIB"pure_quanta";
"2"
$PN"2"82;
"1"
$PN"1"95;
%"Q_CAP_DIFFBUS"
"2","(-4925,2850)","2","pure_quanta","I144";
;
LOCATION"C563"
$SEC"1"
CDS_SEC"1"
VALUE"DIFF BUS_0.22UF"
PACK_TYPE"C0201"
PIN_NAMES_ROTATE"True"
MATERIAL"X6S"
PART_NUMBER"SP_CH4221MEE01"
TOLERANCE"20%"
VOLTAGE"6.3V"
CDS_LMAN_SYM_OUTLINE"-25,50,25,-50"
CDS_LIB"pure_quanta";
"2"
$PN"2"81;
"1"
$PN"1"134;
%"Q_CAP_DIFFBUS"
"2","(-4925,2800)","2","pure_quanta","I145";
;
LOCATION"C564"
$SEC"1"
CDS_SEC"1"
VALUE"DIFF BUS_0.22UF"
VOLTAGE"6.3V"
TOLERANCE"20%"
PART_NUMBER"SP_CH4221MEE01"
MATERIAL"X6S"
PIN_NAMES_ROTATE"True"
PACK_TYPE"C0201"
CDS_LMAN_SYM_OUTLINE"-25,50,25,-50"
CDS_LIB"pure_quanta";
"2"
$PN"2"88;
"1"
$PN"1"101;
%"Q_CAP_DIFFBUS"
"2","(-4925,2750)","2","pure_quanta","I146";
;
LOCATION"C565"
$SEC"1"
CDS_SEC"1"
VALUE"DIFF BUS_0.22UF"
PACK_TYPE"C0201"
PIN_NAMES_ROTATE"True"
MATERIAL"X6S"
PART_NUMBER"SP_CH4221MEE01"
TOLERANCE"20%"
VOLTAGE"6.3V"
CDS_LMAN_SYM_OUTLINE"-25,50,25,-50"
CDS_LIB"pure_quanta";
"2"
$PN"2"90;
"1"
$PN"1"102;
%"Q_CAP_DIFFBUS"
"2","(-4925,2700)","2","pure_quanta","I147";
;
LOCATION"C566"
$SEC"1"
CDS_SEC"1"
VALUE"DIFF BUS_0.22UF"
PACK_TYPE"C0201"
PIN_NAMES_ROTATE"True"
MATERIAL"X6S"
PART_NUMBER"SP_CH4221MEE01"
TOLERANCE"20%"
VOLTAGE"6.3V"
CDS_LMAN_SYM_OUTLINE"-25,50,25,-50"
CDS_LIB"pure_quanta";
"2"
$PN"2"85;
"1"
$PN"1"103;
%"Q_CAP_DIFFBUS"
"2","(-4925,2650)","2","pure_quanta","I148";
;
LOCATION"C567"
$SEC"1"
CDS_SEC"1"
VALUE"DIFF BUS_0.22UF"
PACK_TYPE"C0201"
PIN_NAMES_ROTATE"True"
MATERIAL"X6S"
PART_NUMBER"SP_CH4221MEE01"
TOLERANCE"20%"
VOLTAGE"6.3V"
CDS_LMAN_SYM_OUTLINE"-25,50,25,-50"
CDS_LIB"pure_quanta";
"2"
$PN"2"89;
"1"
$PN"1"104;
%"Q_CAP_DIFFBUS"
"2","(-4925,2600)","2","pure_quanta","I149";
;
LOCATION"C568"
$SEC"1"
CDS_SEC"1"
VALUE"DIFF BUS_0.22UF"
PACK_TYPE"C0201"
PIN_NAMES_ROTATE"True"
MATERIAL"X6S"
PART_NUMBER"SP_CH4221MEE01"
TOLERANCE"20%"
VOLTAGE"6.3V"
CDS_LMAN_SYM_OUTLINE"-25,50,25,-50"
CDS_LIB"pure_quanta";
"2"
$PN"2"79;
"1"
$PN"1"105;
%"TAP"
"6","(-5800,5150)","0","standard","I15";
;
CDS_LIB"standard"
BODY_TYPE"PLUMBING"
HDL_TAP"TRUE";
"B \NAC \NWC"3;
"S \NAC"
BN"6"14;
%"Q_CAP_DIFFBUS"
"2","(-4925,2500)","2","pure_quanta","I150";
;
LOCATION"C570"
$SEC"1"
CDS_SEC"1"
VALUE"DIFF BUS_0.22UF"
PACK_TYPE"C0201"
PIN_NAMES_ROTATE"True"
MATERIAL"X6S"
PART_NUMBER"SP_CH4221MEE01"
TOLERANCE"20%"
VOLTAGE"6.3V"
CDS_LMAN_SYM_OUTLINE"-25,50,25,-50"
CDS_LIB"pure_quanta";
"2"
$PN"2"76;
"1"
$PN"1"106;
%"Q_CAP_DIFFBUS"
"2","(-4925,2550)","2","pure_quanta","I151";
;
LOCATION"C569"
$SEC"1"
CDS_SEC"1"
VALUE"DIFF BUS_0.22UF"
PACK_TYPE"C0201"
PIN_NAMES_ROTATE"True"
MATERIAL"X6S"
PART_NUMBER"SP_CH4221MEE01"
TOLERANCE"20%"
VOLTAGE"6.3V"
CDS_LMAN_SYM_OUTLINE"-25,50,25,-50"
CDS_LIB"pure_quanta";
"2"
$PN"2"77;
"1"
$PN"1"80;
%"Q_CAP_DIFFBUS"
"2","(-4925,2450)","2","pure_quanta","I152";
;
LOCATION"C571"
$SEC"1"
CDS_SEC"1"
VALUE"DIFF BUS_0.22UF"
VOLTAGE"6.3V"
TOLERANCE"20%"
PART_NUMBER"SP_CH4221MEE01"
MATERIAL"X6S"
PIN_NAMES_ROTATE"True"
PACK_TYPE"C0201"
CDS_LMAN_SYM_OUTLINE"-25,50,25,-50"
CDS_LIB"pure_quanta";
"2"
$PN"2"75;
"1"
$PN"1"107;
%"Q_CAP_DIFFBUS"
"2","(-4925,2400)","2","pure_quanta","I153";
;
LOCATION"C572"
$SEC"1"
CDS_SEC"1"
VALUE"DIFF BUS_0.22UF"
PACK_TYPE"C0201"
PIN_NAMES_ROTATE"True"
MATERIAL"X6S"
PART_NUMBER"SP_CH4221MEE01"
TOLERANCE"20%"
VOLTAGE"6.3V"
CDS_LMAN_SYM_OUTLINE"-25,50,25,-50"
CDS_LIB"pure_quanta";
"2"
$PN"2"78;
"1"
$PN"1"74;
%"Q_CAP_DIFFBUS"
"2","(-4925,2350)","2","pure_quanta","I154";
;
LOCATION"C573"
$SEC"1"
CDS_SEC"1"
VALUE"DIFF BUS_0.22UF"
PACK_TYPE"C0201"
PIN_NAMES_ROTATE"True"
MATERIAL"X6S"
PART_NUMBER"SP_CH4221MEE01"
TOLERANCE"20%"
VOLTAGE"6.3V"
CDS_LMAN_SYM_OUTLINE"-25,50,25,-50"
CDS_LIB"pure_quanta";
"2"
$PN"2"64;
"1"
$PN"1"73;
%"Q_CAP_DIFFBUS"
"2","(-4925,2250)","2","pure_quanta","I155";
;
LOCATION"C575"
$SEC"1"
CDS_SEC"1"
VALUE"DIFF BUS_0.22UF"
VOLTAGE"6.3V"
TOLERANCE"20%"
PART_NUMBER"SP_CH4221MEE01"
MATERIAL"X6S"
PIN_NAMES_ROTATE"True"
PACK_TYPE"C0201"
CDS_LMAN_SYM_OUTLINE"-25,50,25,-50"
CDS_LIB"pure_quanta";
"2"
$PN"2"62;
"1"
$PN"1"71;
%"Q_CAP_DIFFBUS"
"2","(-4925,2300)","2","pure_quanta","I156";
;
LOCATION"C574"
$SEC"1"
CDS_SEC"1"
VALUE"DIFF BUS_0.22UF"
PACK_TYPE"C0201"
PIN_NAMES_ROTATE"True"
MATERIAL"X6S"
PART_NUMBER"SP_CH4221MEE01"
TOLERANCE"20%"
VOLTAGE"6.3V"
CDS_LMAN_SYM_OUTLINE"-25,50,25,-50"
CDS_LIB"pure_quanta";
"2"
$PN"2"63;
"1"
$PN"1"72;
%"Q_CAP_DIFFBUS"
"2","(-4925,2200)","2","pure_quanta","I157";
;
LOCATION"C576"
$SEC"1"
CDS_SEC"1"
VALUE"DIFF BUS_0.22UF"
PACK_TYPE"C0201"
PIN_NAMES_ROTATE"True"
MATERIAL"X6S"
PART_NUMBER"SP_CH4221MEE01"
TOLERANCE"20%"
VOLTAGE"6.3V"
CDS_LMAN_SYM_OUTLINE"-25,50,25,-50"
CDS_LIB"pure_quanta";
"2"
$PN"2"61;
"1"
$PN"1"70;
%"Q_CAP_DIFFBUS"
"2","(-4925,2150)","2","pure_quanta","I158";
;
LOCATION"C577"
$SEC"1"
CDS_SEC"1"
VALUE"DIFF BUS_0.22UF"
PACK_TYPE"C0201"
PIN_NAMES_ROTATE"True"
MATERIAL"X6S"
PART_NUMBER"SP_CH4221MEE01"
TOLERANCE"20%"
VOLTAGE"6.3V"
CDS_LMAN_SYM_OUTLINE"-25,50,25,-50"
CDS_LIB"pure_quanta";
"2"
$PN"2"53;
"1"
$PN"1"69;
%"Q_CAP_DIFFBUS"
"2","(-4925,2100)","2","pure_quanta","I159";
;
LOCATION"C578"
$SEC"1"
CDS_SEC"1"
VALUE"DIFF BUS_0.22UF"
PACK_TYPE"C0201"
PIN_NAMES_ROTATE"True"
MATERIAL"X6S"
PART_NUMBER"SP_CH4221MEE01"
TOLERANCE"20%"
VOLTAGE"6.3V"
CDS_LMAN_SYM_OUTLINE"-25,50,25,-50"
CDS_LIB"pure_quanta";
"2"
$PN"2"60;
"1"
$PN"1"68;
%"TAP"
"6","(-5650,4700)","0","standard","I16";
;
CDS_LIB"standard"
BODY_TYPE"PLUMBING"
HDL_TAP"TRUE";
"B \NAC \NWC"2;
"S \NAC"
BN"11"125;
%"Q_CAP_DIFFBUS"
"2","(-4925,2050)","2","pure_quanta","I160";
;
LOCATION"C579"
$SEC"1"
CDS_SEC"1"
VALUE"DIFF BUS_0.22UF"
PACK_TYPE"C0201"
PIN_NAMES_ROTATE"True"
MATERIAL"X6S"
PART_NUMBER"SP_CH4221MEE01"
TOLERANCE"20%"
VOLTAGE"6.3V"
CDS_LMAN_SYM_OUTLINE"-25,50,25,-50"
CDS_LIB"pure_quanta";
"2"
$PN"2"56;
"1"
$PN"1"59;
%"Q_CAP_DIFFBUS"
"2","(-4925,2000)","2","pure_quanta","I161";
;
LOCATION"C580"
$SEC"1"
CDS_SEC"1"
VALUE"DIFF BUS_0.22UF"
PACK_TYPE"C0201"
PIN_NAMES_ROTATE"True"
MATERIAL"X6S"
PART_NUMBER"SP_CH4221MEE01"
TOLERANCE"20%"
VOLTAGE"6.3V"
CDS_LMAN_SYM_OUTLINE"-25,50,25,-50"
CDS_LIB"pure_quanta";
"2"
$PN"2"55;
"1"
$PN"1"58;
%"Q_CAP_DIFFBUS"
"2","(-4925,1950)","2","pure_quanta","I162";
;
LOCATION"C581"
$SEC"1"
CDS_SEC"1"
VALUE"DIFF BUS_0.22UF"
PACK_TYPE"C0201"
PIN_NAMES_ROTATE"True"
MATERIAL"X6S"
PART_NUMBER"SP_CH4221MEE01"
TOLERANCE"20%"
VOLTAGE"6.3V"
CDS_LMAN_SYM_OUTLINE"-25,50,25,-50"
CDS_LIB"pure_quanta";
"2"
$PN"2"54;
"1"
$PN"1"65;
%"Q_CAP_DIFFBUS"
"2","(-4925,1900)","2","pure_quanta","I163";
;
LOCATION"C582"
$SEC"1"
CDS_SEC"1"
VALUE"DIFF BUS_0.22UF"
VOLTAGE"6.3V"
TOLERANCE"20%"
PART_NUMBER"SP_CH4221MEE01"
MATERIAL"X6S"
PIN_NAMES_ROTATE"True"
PACK_TYPE"C0201"
CDS_LMAN_SYM_OUTLINE"-25,50,25,-50"
CDS_LIB"pure_quanta";
"2"
$PN"2"52;
"1"
$PN"1"66;
%"Q_CAP_DIFFBUS"
"2","(-4925,1800)","2","pure_quanta","I164";
;
LOCATION"C585"
$SEC"1"
CDS_SEC"1"
VALUE"DIFF BUS_0.22UF"
VOLTAGE"6.3V"
TOLERANCE"20%"
PART_NUMBER"SP_CH4221MEE01"
MATERIAL"X6S"
PIN_NAMES_ROTATE"True"
PACK_TYPE"C0201"
CDS_LMAN_SYM_OUTLINE"-25,50,25,-50"
CDS_LIB"pure_quanta";
"2"
$PN"2"50;
"1"
$PN"1"57;
%"Q_CAP_DIFFBUS"
"2","(-4925,1750)","2","pure_quanta","I165";
;
LOCATION"C586"
$SEC"1"
CDS_SEC"1"
VALUE"DIFF BUS_0.22UF"
VOLTAGE"6.3V"
TOLERANCE"20%"
PART_NUMBER"SP_CH4221MEE01"
MATERIAL"X6S"
PIN_NAMES_ROTATE"True"
PACK_TYPE"C0201"
CDS_LMAN_SYM_OUTLINE"-25,50,25,-50"
CDS_LIB"pure_quanta";
"2"
$PN"2"51;
"1"
$PN"1"136;
%"Q_CAP_DIFFBUS"
"2","(-4925,1850)","2","pure_quanta","I166";
;
LOCATION"C583"
$SEC"1"
CDS_SEC"1"
VALUE"DIFF BUS_0.22UF"
VOLTAGE"6.3V"
TOLERANCE"20%"
PART_NUMBER"SP_CH4221MEE01"
MATERIAL"X6S"
PIN_NAMES_ROTATE"True"
PACK_TYPE"C0201"
CDS_LMAN_SYM_OUTLINE"-25,50,25,-50"
CDS_LIB"pure_quanta";
"2"
$PN"2"49;
"1"
$PN"1"67;
%"TAP"
"6","(-5650,3300)","0","standard","I167";
;
HDL_TAP"TRUE"
BODY_TYPE"PLUMBING"
CDS_LIB"standard";
"B \NAC \NWC"5;
"S \NAC"
BN"0"110;
%"TAP"
"6","(-5650,3200)","0","standard","I168";
;
HDL_TAP"TRUE"
BODY_TYPE"PLUMBING"
CDS_LIB"standard";
"B \NAC \NWC"5;
"S \NAC"
BN"1"92;
%"TAP"
"6","(-5800,3150)","0","standard","I169";
;
HDL_TAP"TRUE"
BODY_TYPE"PLUMBING"
CDS_LIB"standard";
"B \NAC \NWC"6;
"S \NAC"
BN"1"87;
%"TAP"
"6","(-5650,4900)","0","standard","I17";
;
CDS_LIB"standard"
BODY_TYPE"PLUMBING"
HDL_TAP"TRUE";
"B \NAC \NWC"2;
"S \NAC"
BN"9"126;
%"TAP"
"6","(-5800,3250)","0","standard","I170";
;
HDL_TAP"TRUE"
BODY_TYPE"PLUMBING"
CDS_LIB"standard";
"B \NAC \NWC"6;
"S \NAC"
BN"0"93;
%"TAP"
"6","(-5650,3100)","0","standard","I171";
;
HDL_TAP"TRUE"
BODY_TYPE"PLUMBING"
CDS_LIB"standard";
"B \NAC \NWC"5;
"S \NAC"
BN"2"91;
%"TAP"
"6","(-5650,2900)","0","standard","I172";
;
HDL_TAP"TRUE"
BODY_TYPE"PLUMBING"
CDS_LIB"standard";
"B \NAC \NWC"5;
"S \NAC"
BN"4"82;
%"TAP"
"6","(-5650,3000)","0","standard","I173";
;
HDL_TAP"TRUE"
BODY_TYPE"PLUMBING"
CDS_LIB"standard";
"B \NAC \NWC"5;
"S \NAC"
BN"3"84;
%"TAP"
"6","(-5800,3050)","0","standard","I174";
;
HDL_TAP"TRUE"
BODY_TYPE"PLUMBING"
CDS_LIB"standard";
"B \NAC \NWC"6;
"S \NAC"
BN"2"86;
%"TAP"
"6","(-5800,2950)","0","standard","I175";
;
HDL_TAP"TRUE"
BODY_TYPE"PLUMBING"
CDS_LIB"standard";
"B \NAC \NWC"6;
"S \NAC"
BN"3"83;
%"TAP"
"6","(-5650,2800)","0","standard","I176";
;
HDL_TAP"TRUE"
BODY_TYPE"PLUMBING"
CDS_LIB"standard";
"B \NAC \NWC"5;
"S \NAC"
BN"5"88;
%"TAP"
"6","(-5650,2700)","0","standard","I177";
;
HDL_TAP"TRUE"
BODY_TYPE"PLUMBING"
CDS_LIB"standard";
"B \NAC \NWC"5;
"S \NAC"
BN"6"85;
%"TAP"
"6","(-5800,2750)","0","standard","I178";
;
HDL_TAP"TRUE"
BODY_TYPE"PLUMBING"
CDS_LIB"standard";
"B \NAC \NWC"6;
"S \NAC"
BN"5"90;
%"TAP"
"6","(-5800,2850)","0","standard","I179";
;
HDL_TAP"TRUE"
BODY_TYPE"PLUMBING"
CDS_LIB"standard";
"B \NAC \NWC"6;
"S \NAC"
BN"4"81;
%"TAP"
"6","(-5650,4800)","0","standard","I18";
;
CDS_LIB"standard"
BODY_TYPE"PLUMBING"
HDL_TAP"TRUE";
"B \NAC \NWC"2;
"S \NAC"
BN"10"122;
%"TAP"
"6","(-5800,2650)","0","standard","I180";
;
HDL_TAP"TRUE"
BODY_TYPE"PLUMBING"
CDS_LIB"standard";
"B \NAC \NWC"6;
"S \NAC"
BN"6"89;
%"TAP"
"6","(-5650,2600)","0","standard","I181";
;
HDL_TAP"TRUE"
BODY_TYPE"PLUMBING"
CDS_LIB"standard";
"B \NAC \NWC"5;
"S \NAC"
BN"7"79;
%"TAP"
"6","(-5650,2500)","0","standard","I182";
;
HDL_TAP"TRUE"
BODY_TYPE"PLUMBING"
CDS_LIB"standard";
"B \NAC \NWC"5;
"S \NAC"
BN"8"76;
%"TAP"
"6","(-5650,2400)","0","standard","I183";
;
HDL_TAP"TRUE"
BODY_TYPE"PLUMBING"
CDS_LIB"standard";
"B \NAC \NWC"5;
"S \NAC"
BN"9"78;
%"TAP"
"6","(-5800,2550)","0","standard","I184";
;
HDL_TAP"TRUE"
BODY_TYPE"PLUMBING"
CDS_LIB"standard";
"B \NAC \NWC"6;
"S \NAC"
BN"7"77;
%"TAP"
"6","(-5800,2450)","0","standard","I185";
;
HDL_TAP"TRUE"
BODY_TYPE"PLUMBING"
CDS_LIB"standard";
"B \NAC \NWC"6;
"S \NAC"
BN"8"75;
%"TAP"
"6","(-5650,2300)","0","standard","I186";
;
HDL_TAP"TRUE"
BODY_TYPE"PLUMBING"
CDS_LIB"standard";
"B \NAC \NWC"5;
"S \NAC"
BN"10"63;
%"TAP"
"6","(-5650,2200)","0","standard","I187";
;
HDL_TAP"TRUE"
BODY_TYPE"PLUMBING"
CDS_LIB"standard";
"B \NAC \NWC"5;
"S \NAC"
BN"11"61;
%"TAP"
"6","(-5800,2350)","0","standard","I188";
;
HDL_TAP"TRUE"
BODY_TYPE"PLUMBING"
CDS_LIB"standard";
"B \NAC \NWC"6;
"S \NAC"
BN"9"64;
%"TAP"
"6","(-5800,2250)","0","standard","I189";
;
HDL_TAP"TRUE"
BODY_TYPE"PLUMBING"
CDS_LIB"standard";
"B \NAC \NWC"6;
"S \NAC"
BN"10"62;
%"TAP"
"6","(-5800,5350)","0","standard","I19";
;
CDS_LIB"standard"
BODY_TYPE"PLUMBING"
HDL_TAP"TRUE";
"B \NAC \NWC"3;
"S \NAC"
BN"4"21;
%"TAP"
"6","(-5800,2150)","0","standard","I190";
;
HDL_TAP"TRUE"
BODY_TYPE"PLUMBING"
CDS_LIB"standard";
"B \NAC \NWC"6;
"S \NAC"
BN"11"53;
%"TAP"
"6","(-5650,2000)","0","standard","I191";
;
HDL_TAP"TRUE"
BODY_TYPE"PLUMBING"
CDS_LIB"standard";
"B \NAC \NWC"5;
"S \NAC"
BN"13"55;
%"TAP"
"6","(-5650,2100)","0","standard","I192";
;
HDL_TAP"TRUE"
BODY_TYPE"PLUMBING"
CDS_LIB"standard";
"B \NAC \NWC"5;
"S \NAC"
BN"12"60;
%"TAP"
"6","(-5650,1900)","0","standard","I193";
;
HDL_TAP"TRUE"
BODY_TYPE"PLUMBING"
CDS_LIB"standard";
"B \NAC \NWC"5;
"S \NAC"
BN"14"52;
%"TAP"
"6","(-5800,2050)","0","standard","I194";
;
HDL_TAP"TRUE"
BODY_TYPE"PLUMBING"
CDS_LIB"standard";
"B \NAC \NWC"6;
"S \NAC"
BN"12"56;
%"TAP"
"6","(-5800,1950)","0","standard","I195";
;
HDL_TAP"TRUE"
BODY_TYPE"PLUMBING"
CDS_LIB"standard";
"B \NAC \NWC"6;
"S \NAC"
BN"13"54;
%"TAP"
"6","(-5650,1800)","0","standard","I196";
;
HDL_TAP"TRUE"
BODY_TYPE"PLUMBING"
CDS_LIB"standard";
"B \NAC \NWC"5;
"S \NAC"
BN"15"50;
%"TAP"
"6","(-5800,1850)","0","standard","I197";
;
HDL_TAP"TRUE"
BODY_TYPE"PLUMBING"
CDS_LIB"standard";
"B \NAC \NWC"6;
"S \NAC"
BN"14"49;
%"TAP"
"6","(-5800,1750)","0","standard","I198";
;
HDL_TAP"TRUE"
BODY_TYPE"PLUMBING"
CDS_LIB"standard";
"B \NAC \NWC"6;
"S \NAC"
BN"15"51;
%"TAP"
"6","(-5800,4250)","0","standard","I2";
;
CDS_LIB"standard"
BODY_TYPE"PLUMBING"
HDL_TAP"TRUE";
"B \NAC \NWC"3;
"S \NAC"
BN"15"115;
%"TAP"
"6","(-5800,5450)","0","standard","I20";
;
CDS_LIB"standard"
BODY_TYPE"PLUMBING"
HDL_TAP"TRUE";
"B \NAC \NWC"3;
"S \NAC"
BN"3"131;
%"TAP"
"6","(-5800,5550)","0","standard","I21";
;
CDS_LIB"standard"
BODY_TYPE"PLUMBING"
HDL_TAP"TRUE";
"B \NAC \NWC"3;
"S \NAC"
BN"2"112;
%"TAP"
"6","(-5800,5650)","0","standard","I22";
;
CDS_LIB"standard"
BODY_TYPE"PLUMBING"
HDL_TAP"TRUE";
"B \NAC \NWC"3;
"S \NAC"
BN"1"18;
%"TAP"
"6","(-5650,5200)","0","standard","I23";
;
CDS_LIB"standard"
BODY_TYPE"PLUMBING"
HDL_TAP"TRUE";
"B \NAC \NWC"2;
"S \NAC"
BN"6"13;
%"TAP"
"6","(-5650,5300)","0","standard","I24";
;
CDS_LIB"standard"
BODY_TYPE"PLUMBING"
HDL_TAP"TRUE";
"B \NAC \NWC"2;
"S \NAC"
BN"5"10;
%"TAP"
"6","(-5650,5400)","0","standard","I25";
;
CDS_LIB"standard"
BODY_TYPE"PLUMBING"
HDL_TAP"TRUE";
"B \NAC \NWC"2;
"S \NAC"
BN"4"20;
%"TAP"
"6","(-5650,5500)","0","standard","I26";
;
CDS_LIB"standard"
BODY_TYPE"PLUMBING"
HDL_TAP"TRUE";
"B \NAC \NWC"2;
"S \NAC"
BN"3"111;
%"TAP"
"6","(-5650,5600)","0","standard","I27";
;
CDS_LIB"standard"
BODY_TYPE"PLUMBING"
HDL_TAP"TRUE";
"B \NAC \NWC"2;
"S \NAC"
BN"2"19;
%"TAP"
"6","(-5650,5700)","0","standard","I28";
;
CDS_LIB"standard"
BODY_TYPE"PLUMBING"
HDL_TAP"TRUE";
"B \NAC \NWC"2;
"S \NAC"
BN"1"132;
%"TAP"
"6","(-5800,5750)","0","standard","I29";
;
CDS_LIB"standard"
BODY_TYPE"PLUMBING"
HDL_TAP"TRUE";
"B \NAC \NWC"3;
"S \NAC"
BN"0"133;
%"TAP"
"6","(-5800,4350)","0","standard","I3";
;
CDS_LIB"standard"
BODY_TYPE"PLUMBING"
HDL_TAP"TRUE";
"B \NAC \NWC"3;
"S \NAC"
BN"14"116;
%"TAP"
"6","(-5650,5800)","0","standard","I30";
;
CDS_LIB"standard"
BODY_TYPE"PLUMBING"
HDL_TAP"TRUE";
"B \NAC \NWC"2;
"S \NAC"
BN"0"135;
%"Q_CAP_DIFFBUS"
"2","(-4925,4300)","2","pure_quanta","I31";
;
LOCATION"C540"
$SEC"1"
CDS_SEC"1"
VALUE"DIFF BUS_0.22UF"
CDS_LMAN_SYM_OUTLINE"-25,50,25,-50"
CDS_LIB"pure_quanta"
PACK_TYPE"C0201"
PIN_NAMES_ROTATE"True"
MATERIAL"X6S"
PART_NUMBER"SP_CH4221MEE01"
TOLERANCE"20%"
VOLTAGE"6.3V";
"2"
$PN"2"114;
"1"
$PN"1"26;
%"Q_CAP_DIFFBUS"
"2","(-4925,4250)","2","pure_quanta","I32";
;
LOCATION"C541"
$SEC"1"
CDS_SEC"1"
VALUE"DIFF BUS_0.22UF"
CDS_LMAN_SYM_OUTLINE"-25,50,25,-50"
CDS_LIB"pure_quanta"
PACK_TYPE"C0201"
PIN_NAMES_ROTATE"True"
MATERIAL"X6S"
PART_NUMBER"SP_CH4221MEE01"
TOLERANCE"20%"
VOLTAGE"6.3V";
"2"
$PN"2"115;
"1"
$PN"1"25;
%"Q_CAP_DIFFBUS"
"2","(-4925,4350)","2","pure_quanta","I33";
;
LOCATION"C539"
$SEC"1"
CDS_SEC"1"
VALUE"DIFF BUS_0.22UF"
CDS_LMAN_SYM_OUTLINE"-25,50,25,-50"
CDS_LIB"pure_quanta"
PACK_TYPE"C0201"
PIN_NAMES_ROTATE"True"
MATERIAL"X6S"
PART_NUMBER"SP_CH4221MEE01"
TOLERANCE"20%"
VOLTAGE"6.3V";
"2"
$PN"2"116;
"1"
$PN"1"27;
%"Q_CAP_DIFFBUS"
"2","(-4925,4400)","2","pure_quanta","I34";
;
LOCATION"C538"
$SEC"1"
CDS_SEC"1"
VALUE"DIFF BUS_0.22UF"
CDS_LMAN_SYM_OUTLINE"-25,50,25,-50"
CDS_LIB"pure_quanta"
PACK_TYPE"C0201"
PIN_NAMES_ROTATE"True"
MATERIAL"X6S"
PART_NUMBER"SP_CH4221MEE01"
TOLERANCE"20%"
VOLTAGE"6.3V";
"2"
$PN"2"117;
"1"
$PN"1"28;
%"Q_CAP_DIFFBUS"
"2","(-4925,4450)","2","pure_quanta","I35";
;
LOCATION"C529"
$SEC"1"
CDS_SEC"1"
VALUE"DIFF BUS_0.22UF"
CDS_LMAN_SYM_OUTLINE"-25,50,25,-50"
CDS_LIB"pure_quanta"
VOLTAGE"6.3V"
TOLERANCE"20%"
PART_NUMBER"SP_CH4221MEE01"
MATERIAL"X6S"
PIN_NAMES_ROTATE"True"
PACK_TYPE"C0201";
"2"
$PN"2"113;
"1"
$PN"1"29;
%"Q_CAP_DIFFBUS"
"2","(-4925,4500)","2","pure_quanta","I36";
;
LOCATION"C528"
$SEC"1"
CDS_SEC"1"
VALUE"DIFF BUS_0.22UF"
CDS_LMAN_SYM_OUTLINE"-25,50,25,-50"
CDS_LIB"pure_quanta"
VOLTAGE"6.3V"
TOLERANCE"20%"
PART_NUMBER"SP_CH4221MEE01"
MATERIAL"X6S"
PIN_NAMES_ROTATE"True"
PACK_TYPE"C0201";
"2"
$PN"2"124;
"1"
$PN"1"30;
%"Q_CAP_DIFFBUS"
"2","(-4925,4550)","2","pure_quanta","I37";
;
LOCATION"C526"
$SEC"1"
CDS_SEC"1"
VALUE"DIFF BUS_0.22UF"
CDS_LMAN_SYM_OUTLINE"-25,50,25,-50"
CDS_LIB"pure_quanta"
VOLTAGE"6.3V"
TOLERANCE"20%"
PART_NUMBER"SP_CH4221MEE01"
MATERIAL"X6S"
PIN_NAMES_ROTATE"True"
PACK_TYPE"C0201";
"2"
$PN"2"120;
"1"
$PN"1"31;
%"Q_CAP_DIFFBUS"
"2","(-4925,4650)","2","pure_quanta","I38";
;
LOCATION"C524"
$SEC"1"
CDS_SEC"1"
VALUE"DIFF BUS_0.22UF"
CDS_LMAN_SYM_OUTLINE"-25,50,25,-50"
CDS_LIB"pure_quanta"
VOLTAGE"6.3V"
TOLERANCE"20%"
PART_NUMBER"SP_CH4221MEE01"
MATERIAL"X6S"
PIN_NAMES_ROTATE"True"
PACK_TYPE"C0201";
"2"
$PN"2"118;
"1"
$PN"1"33;
%"Q_CAP_DIFFBUS"
"2","(-4925,4600)","2","pure_quanta","I39";
;
LOCATION"C525"
$SEC"1"
CDS_SEC"1"
VALUE"DIFF BUS_0.22UF"
CDS_LMAN_SYM_OUTLINE"-25,50,25,-50"
CDS_LIB"pure_quanta"
VOLTAGE"6.3V"
TOLERANCE"20%"
PART_NUMBER"SP_CH4221MEE01"
MATERIAL"X6S"
PIN_NAMES_ROTATE"True"
PACK_TYPE"C0201";
"2"
$PN"2"119;
"1"
$PN"1"32;
%"TAP"
"6","(-5800,4550)","0","standard","I4";
;
CDS_LIB"standard"
BODY_TYPE"PLUMBING"
HDL_TAP"TRUE";
"B \NAC \NWC"3;
"S \NAC"
BN"12"120;
%"Q_CAP_DIFFBUS"
"2","(-4925,4700)","2","pure_quanta","I40";
;
LOCATION"C523"
$SEC"1"
CDS_SEC"1"
VALUE"DIFF BUS_0.22UF"
CDS_LMAN_SYM_OUTLINE"-25,50,25,-50"
CDS_LIB"pure_quanta"
VOLTAGE"6.3V"
TOLERANCE"20%"
PART_NUMBER"SP_CH4221MEE01"
MATERIAL"X6S"
PIN_NAMES_ROTATE"True"
PACK_TYPE"C0201";
"2"
$PN"2"125;
"1"
$PN"1"34;
%"Q_CAP_DIFFBUS"
"2","(-4925,4800)","2","pure_quanta","I41";
;
LOCATION"C521"
$SEC"1"
CDS_SEC"1"
VALUE"DIFF BUS_0.22UF"
CDS_LMAN_SYM_OUTLINE"-25,50,25,-50"
CDS_LIB"pure_quanta"
VOLTAGE"6.3V"
TOLERANCE"20%"
PART_NUMBER"SP_CH4221MEE01"
MATERIAL"X6S"
PIN_NAMES_ROTATE"True"
PACK_TYPE"C0201";
"2"
$PN"2"122;
"1"
$PN"1"36;
%"Q_CAP_DIFFBUS"
"2","(-4925,4750)","2","pure_quanta","I42";
;
LOCATION"C522"
$SEC"1"
CDS_SEC"1"
VALUE"DIFF BUS_0.22UF"
CDS_LMAN_SYM_OUTLINE"-25,50,25,-50"
CDS_LIB"pure_quanta"
PACK_TYPE"C0201"
PIN_NAMES_ROTATE"True"
MATERIAL"X6S"
PART_NUMBER"SP_CH4221MEE01"
TOLERANCE"20%"
VOLTAGE"6.3V";
"2"
$PN"2"123;
"1"
$PN"1"35;
%"Q_CAP_DIFFBUS"
"2","(-4925,4900)","2","pure_quanta","I43";
;
LOCATION"C519"
$SEC"1"
CDS_SEC"1"
VALUE"DIFF BUS_0.22UF"
CDS_LMAN_SYM_OUTLINE"-25,50,25,-50"
CDS_LIB"pure_quanta"
VOLTAGE"6.3V"
TOLERANCE"20%"
PART_NUMBER"SP_CH4221MEE01"
MATERIAL"X6S"
PIN_NAMES_ROTATE"True"
PACK_TYPE"C0201";
"2"
$PN"2"126;
"1"
$PN"1"38;
%"Q_CAP_DIFFBUS"
"2","(-4925,4950)","2","pure_quanta","I44";
;
LOCATION"C517"
$SEC"1"
CDS_SEC"1"
VALUE"DIFF BUS_0.22UF"
CDS_LMAN_SYM_OUTLINE"-25,50,25,-50"
CDS_LIB"pure_quanta"
PACK_TYPE"C0201"
PIN_NAMES_ROTATE"True"
MATERIAL"X6S"
PART_NUMBER"SP_CH4221MEE01"
TOLERANCE"20%"
VOLTAGE"6.3V";
"2"
$PN"2"17;
"1"
$PN"1"39;
%"Q_CAP_DIFFBUS"
"2","(-4925,5050)","2","pure_quanta","I45";
;
LOCATION"C515"
$SEC"1"
CDS_SEC"1"
VALUE"DIFF BUS_0.22UF"
CDS_LMAN_SYM_OUTLINE"-25,50,25,-50"
CDS_LIB"pure_quanta"
VOLTAGE"6.3V"
TOLERANCE"20%"
PART_NUMBER"SP_CH4221MEE01"
MATERIAL"X6S"
PIN_NAMES_ROTATE"True"
PACK_TYPE"C0201";
"2"
$PN"2"15;
"1"
$PN"1"22;
%"Q_CAP_DIFFBUS"
"2","(-4925,5000)","2","pure_quanta","I46";
;
LOCATION"C516"
$SEC"1"
CDS_SEC"1"
VALUE"DIFF BUS_0.22UF"
CDS_LMAN_SYM_OUTLINE"-25,50,25,-50"
CDS_LIB"pure_quanta"
VOLTAGE"6.3V"
TOLERANCE"20%"
PART_NUMBER"SP_CH4221MEE01"
MATERIAL"X6S"
PIN_NAMES_ROTATE"True"
PACK_TYPE"C0201";
"2"
$PN"2"16;
"1"
$PN"1"40;
%"Q_CAP_DIFFBUS"
"2","(-4925,5150)","2","pure_quanta","I47";
;
LOCATION"C513"
$SEC"1"
CDS_SEC"1"
VALUE"DIFF BUS_0.22UF"
CDS_LMAN_SYM_OUTLINE"-25,50,25,-50"
CDS_LIB"pure_quanta"
VOLTAGE"6.3V"
TOLERANCE"20%"
PART_NUMBER"SP_CH4221MEE01"
MATERIAL"X6S"
PIN_NAMES_ROTATE"True"
PACK_TYPE"C0201";
"2"
$PN"2"14;
"1"
$PN"1"23;
%"Q_CAP_DIFFBUS"
"2","(-4925,5100)","2","pure_quanta","I48";
;
LOCATION"C514"
$SEC"1"
CDS_SEC"1"
VALUE"DIFF BUS_0.22UF"
CDS_LMAN_SYM_OUTLINE"-25,50,25,-50"
CDS_LIB"pure_quanta"
VOLTAGE"6.3V"
TOLERANCE"20%"
PART_NUMBER"SP_CH4221MEE01"
MATERIAL"X6S"
PIN_NAMES_ROTATE"True"
PACK_TYPE"C0201";
"2"
$PN"2"127;
"1"
$PN"1"41;
%"Q_CAP_DIFFBUS"
"2","(-4925,5200)","2","pure_quanta","I49";
;
LOCATION"C512"
$SEC"1"
CDS_SEC"1"
VALUE"DIFF BUS_0.22UF"
CDS_LMAN_SYM_OUTLINE"-25,50,25,-50"
CDS_LIB"pure_quanta"
VOLTAGE"6.3V"
TOLERANCE"20%"
PART_NUMBER"SP_CH4221MEE01"
MATERIAL"X6S"
PIN_NAMES_ROTATE"True"
PACK_TYPE"C0201";
"2"
$PN"2"13;
"1"
$PN"1"42;
%"TAP"
"6","(-5800,4450)","0","standard","I5";
;
CDS_LIB"standard"
BODY_TYPE"PLUMBING"
HDL_TAP"TRUE";
"B \NAC \NWC"3;
"S \NAC"
BN"13"113;
%"Q_CAP_DIFFBUS"
"2","(-4925,5250)","2","pure_quanta","I50";
;
LOCATION"C511"
$SEC"1"
CDS_SEC"1"
VALUE"DIFF BUS_0.22UF"
CDS_LMAN_SYM_OUTLINE"-25,50,25,-50"
CDS_LIB"pure_quanta"
VOLTAGE"6.3V"
TOLERANCE"20%"
PART_NUMBER"SP_CH4221MEE01"
MATERIAL"X6S"
PIN_NAMES_ROTATE"True"
PACK_TYPE"C0201";
"2"
$PN"2"9;
"1"
$PN"1"24;
%"Q_CAP_DIFFBUS"
"2","(-4925,5300)","2","pure_quanta","I51";
;
LOCATION"C510"
$SEC"1"
CDS_SEC"1"
VALUE"DIFF BUS_0.22UF"
CDS_LMAN_SYM_OUTLINE"-25,50,25,-50"
CDS_LIB"pure_quanta"
PACK_TYPE"C0201"
PIN_NAMES_ROTATE"True"
MATERIAL"X6S"
PART_NUMBER"SP_CH4221MEE01"
TOLERANCE"20%"
VOLTAGE"6.3V";
"2"
$PN"2"10;
"1"
$PN"1"128;
%"Q_CAP_DIFFBUS"
"2","(-4925,5350)","2","pure_quanta","I52";
;
LOCATION"C542"
$SEC"1"
CDS_SEC"1"
VALUE"DIFF BUS_0.22UF"
CDS_LMAN_SYM_OUTLINE"-25,50,25,-50"
CDS_LIB"pure_quanta"
VOLTAGE"6.3V"
TOLERANCE"20%"
PART_NUMBER"SP_CH4221MEE01"
MATERIAL"X6S"
PIN_NAMES_ROTATE"True"
PACK_TYPE"C0201";
"2"
$PN"2"21;
"1"
$PN"1"12;
%"Q_CAP_DIFFBUS"
"2","(-4925,5400)","2","pure_quanta","I53";
;
LOCATION"C508"
$SEC"1"
CDS_SEC"1"
VALUE"DIFF BUS_0.22UF"
CDS_LMAN_SYM_OUTLINE"-25,50,25,-50"
CDS_LIB"pure_quanta"
VOLTAGE"6.3V"
TOLERANCE"20%"
PART_NUMBER"SP_CH4221MEE01"
MATERIAL"X6S"
PIN_NAMES_ROTATE"True"
PACK_TYPE"C0201";
"2"
$PN"2"20;
"1"
$PN"1"11;
%"Q_CAP_DIFFBUS"
"2","(-4925,5450)","2","pure_quanta","I54";
;
LOCATION"C507"
$SEC"1"
CDS_SEC"1"
VALUE"DIFF BUS_0.22UF"
CDS_LMAN_SYM_OUTLINE"-25,50,25,-50"
CDS_LIB"pure_quanta"
PACK_TYPE"C0201"
PIN_NAMES_ROTATE"True"
MATERIAL"X6S"
PART_NUMBER"SP_CH4221MEE01"
TOLERANCE"20%"
VOLTAGE"6.3V";
"2"
$PN"2"131;
"1"
$PN"1"43;
%"Q_CAP_DIFFBUS"
"2","(-4925,5500)","2","pure_quanta","I55";
;
LOCATION"C506"
$SEC"1"
CDS_SEC"1"
VALUE"DIFF BUS_0.22UF"
CDS_LMAN_SYM_OUTLINE"-25,50,25,-50"
CDS_LIB"pure_quanta"
PACK_TYPE"C0201"
PIN_NAMES_ROTATE"True"
MATERIAL"X6S"
PART_NUMBER"SP_CH4221MEE01"
TOLERANCE"20%"
VOLTAGE"6.3V";
"2"
$PN"2"111;
"1"
$PN"1"44;
%"Q_CAP_DIFFBUS"
"2","(-4925,5550)","2","pure_quanta","I56";
;
LOCATION"C505"
$SEC"1"
CDS_SEC"1"
VALUE"DIFF BUS_0.22UF"
CDS_LMAN_SYM_OUTLINE"-25,50,25,-50"
CDS_LIB"pure_quanta"
PACK_TYPE"C0201"
PIN_NAMES_ROTATE"True"
MATERIAL"X6S"
PART_NUMBER"SP_CH4221MEE01"
TOLERANCE"20%"
VOLTAGE"6.3V";
"2"
$PN"2"112;
"1"
$PN"1"45;
%"Q_CAP_DIFFBUS"
"2","(-4925,5600)","2","pure_quanta","I57";
;
LOCATION"C504"
$SEC"1"
CDS_SEC"1"
VALUE"DIFF BUS_0.22UF"
CDS_LMAN_SYM_OUTLINE"-25,50,25,-50"
CDS_LIB"pure_quanta"
VOLTAGE"6.3V"
TOLERANCE"20%"
PART_NUMBER"SP_CH4221MEE01"
MATERIAL"X6S"
PIN_NAMES_ROTATE"True"
PACK_TYPE"C0201";
"2"
$PN"2"19;
"1"
$PN"1"46;
%"Q_CAP_DIFFBUS"
"2","(-4925,5650)","2","pure_quanta","I58";
;
LOCATION"C503"
$SEC"1"
CDS_SEC"1"
VALUE"DIFF BUS_0.22UF"
CDS_LMAN_SYM_OUTLINE"-25,50,25,-50"
CDS_LIB"pure_quanta"
PACK_TYPE"C0201"
PIN_NAMES_ROTATE"True"
MATERIAL"X6S"
PART_NUMBER"SP_CH4221MEE01"
TOLERANCE"20%"
VOLTAGE"6.3V";
"2"
$PN"2"18;
"1"
$PN"1"47;
%"Q_CAP_DIFFBUS"
"2","(-4925,5700)","2","pure_quanta","I59";
;
LOCATION"C502"
$SEC"1"
CDS_SEC"1"
VALUE"DIFF BUS_0.22UF"
CDS_LMAN_SYM_OUTLINE"-25,50,25,-50"
CDS_LIB"pure_quanta"
PACK_TYPE"C0201"
PIN_NAMES_ROTATE"True"
MATERIAL"X6S"
PART_NUMBER"SP_CH4221MEE01"
TOLERANCE"20%"
VOLTAGE"6.3V";
"2"
$PN"2"132;
"1"
$PN"1"48;
%"TAP"
"6","(-5800,4650)","0","standard","I6";
;
CDS_LIB"standard"
BODY_TYPE"PLUMBING"
HDL_TAP"TRUE";
"B \NAC \NWC"3;
"S \NAC"
BN"11"118;
%"Q_CAP_DIFFBUS"
"2","(-4925,5750)","2","pure_quanta","I60";
;
LOCATION"C501"
$SEC"1"
CDS_SEC"1"
VALUE"DIFF BUS_0.22UF"
CDS_LMAN_SYM_OUTLINE"-25,50,25,-50"
CDS_LIB"pure_quanta"
PACK_TYPE"C0201"
PIN_NAMES_ROTATE"True"
MATERIAL"X6S"
PART_NUMBER"SP_CH4221MEE01"
TOLERANCE"20%"
VOLTAGE"6.3V";
"2"
$PN"2"133;
"1"
$PN"1"129;
%"Q_CAP_DIFFBUS"
"2","(-4925,5800)","0","pure_quanta","I61";
;
LOCATION"C500"
$SEC"1"
CDS_SEC"1"
VALUE"DIFF BUS_0.22UF"
PART_NUMBER"SP_CH4221MEE01"
PACK_TYPE"C0201"
MATERIAL"X6S"
VOLTAGE"6.3V"
TOLERANCE"20%"
CDS_LMAN_SYM_OUTLINE"-25,50,25,-50"
CDS_LIB"pure_quanta"
PIN_NAMES_ROTATE"True";
"2"
$PN"2"130;
"1"
$PN"1"135;
%"TAP"
"6","(-3925,4300)","2","standard","I62";
;
CDS_LIB"standard"
ROOM"RISER1"
HDL_TAP"TRUE"
BODY_TYPE"PLUMBING"
BOM_COST"IO_SLOT";
"B \NAC \NWC"7;
"S \NAC"
BN"15"26;
%"TAP"
"6","(-3925,4400)","2","standard","I63";
;
CDS_LIB"standard"
ROOM"RISER1"
HDL_TAP"TRUE"
BODY_TYPE"PLUMBING"
BOM_COST"IO_SLOT";
"B \NAC \NWC"7;
"S \NAC"
BN"14"28;
%"TAP"
"6","(-3775,4350)","2","standard","I64";
;
CDS_LIB"standard"
ROOM"RISER1"
HDL_TAP"TRUE"
BODY_TYPE"PLUMBING"
BOM_COST"IO_SLOT";
"B \NAC \NWC"8;
"S \NAC"
BN"14"27;
%"TAP"
"6","(-3775,4250)","2","standard","I65";
;
CDS_LIB"standard"
ROOM"RISER1"
HDL_TAP"TRUE"
BODY_TYPE"PLUMBING"
BOM_COST"IO_SLOT";
"B \NAC \NWC"8;
"S \NAC"
BN"15"25;
%"TAP"
"6","(-3925,4500)","2","standard","I66";
;
CDS_LIB"standard"
ROOM"RISER1"
HDL_TAP"TRUE"
BODY_TYPE"PLUMBING"
BOM_COST"IO_SLOT";
"B \NAC \NWC"7;
"S \NAC"
BN"13"30;
%"TAP"
"6","(-3925,4600)","2","standard","I67";
;
CDS_LIB"standard"
ROOM"RISER1"
HDL_TAP"TRUE"
BODY_TYPE"PLUMBING"
BOM_COST"IO_SLOT";
"B \NAC \NWC"7;
"S \NAC"
BN"12"32;
%"TAP"
"6","(-3775,4550)","2","standard","I68";
;
CDS_LIB"standard"
ROOM"RISER1"
HDL_TAP"TRUE"
BODY_TYPE"PLUMBING"
BOM_COST"IO_SLOT";
"B \NAC \NWC"8;
"S \NAC"
BN"12"31;
%"TAP"
"6","(-3775,4650)","2","standard","I69";
;
CDS_LIB"standard"
ROOM"RISER1"
HDL_TAP"TRUE"
BODY_TYPE"PLUMBING"
BOM_COST"IO_SLOT";
"B \NAC \NWC"8;
"S \NAC"
BN"11"33;
%"TAP"
"6","(-5650,4300)","0","standard","I7";
;
CDS_LIB"standard"
BODY_TYPE"PLUMBING"
HDL_TAP"TRUE";
"B \NAC \NWC"2;
"S \NAC"
BN"15"114;
%"TAP"
"6","(-3775,4450)","2","standard","I70";
;
CDS_LIB"standard"
ROOM"RISER1"
HDL_TAP"TRUE"
BODY_TYPE"PLUMBING"
BOM_COST"IO_SLOT";
"B \NAC \NWC"8;
"S \NAC"
BN"13"29;
%"TAP"
"6","(-3925,4700)","2","standard","I71";
;
CDS_LIB"standard"
ROOM"RISER1"
HDL_TAP"TRUE"
BODY_TYPE"PLUMBING"
BOM_COST"IO_SLOT";
"B \NAC \NWC"7;
"S \NAC"
BN"11"34;
%"TAP"
"6","(-3925,4800)","2","standard","I72";
;
CDS_LIB"standard"
ROOM"RISER1"
HDL_TAP"TRUE"
BODY_TYPE"PLUMBING"
BOM_COST"IO_SLOT";
"B \NAC \NWC"7;
"S \NAC"
BN"10"36;
%"TAP"
"6","(-3925,4900)","2","standard","I73";
;
CDS_LIB"standard"
ROOM"RISER1"
HDL_TAP"TRUE"
BODY_TYPE"PLUMBING"
BOM_COST"IO_SLOT";
"B \NAC \NWC"7;
"S \NAC"
BN"9"38;
%"TAP"
"6","(-3775,4750)","2","standard","I74";
;
CDS_LIB"standard"
ROOM"RISER1"
HDL_TAP"TRUE"
BODY_TYPE"PLUMBING"
BOM_COST"IO_SLOT";
"B \NAC \NWC"8;
"S \NAC"
BN"10"35;
%"TAP"
"6","(-3775,4850)","2","standard","I75";
;
CDS_LIB"standard"
ROOM"RISER1"
HDL_TAP"TRUE"
BODY_TYPE"PLUMBING"
BOM_COST"IO_SLOT";
"B \NAC \NWC"8;
"S \NAC"
BN"9"37;
%"TAP"
"6","(-3925,5000)","2","standard","I76";
;
CDS_LIB"standard"
ROOM"RISER1"
HDL_TAP"TRUE"
BODY_TYPE"PLUMBING"
BOM_COST"IO_SLOT";
"B \NAC \NWC"7;
"S \NAC"
BN"8"40;
%"TAP"
"6","(-3925,5100)","2","standard","I77";
;
CDS_LIB"standard"
ROOM"RISER1"
HDL_TAP"TRUE"
BODY_TYPE"PLUMBING"
BOM_COST"IO_SLOT";
"B \NAC \NWC"7;
"S \NAC"
BN"7"41;
%"TAP"
"6","(-3775,5150)","2","standard","I78";
;
CDS_LIB"standard"
ROOM"RISER1"
HDL_TAP"TRUE"
BODY_TYPE"PLUMBING"
BOM_COST"IO_SLOT";
"B \NAC \NWC"8;
"S \NAC"
BN"6"23;
%"TAP"
"6","(-3775,5050)","2","standard","I79";
;
CDS_LIB"standard"
ROOM"RISER1"
HDL_TAP"TRUE"
BODY_TYPE"PLUMBING"
BOM_COST"IO_SLOT";
"B \NAC \NWC"8;
"S \NAC"
BN"7"22;
%"TAP"
"6","(-5650,4400)","0","standard","I8";
;
CDS_LIB"standard"
BODY_TYPE"PLUMBING"
HDL_TAP"TRUE";
"B \NAC \NWC"2;
"S \NAC"
BN"14"117;
%"TAP"
"6","(-3775,4950)","2","standard","I80";
;
CDS_LIB"standard"
ROOM"RISER1"
HDL_TAP"TRUE"
BODY_TYPE"PLUMBING"
BOM_COST"IO_SLOT";
"B \NAC \NWC"8;
"S \NAC"
BN"8"39;
%"TAP"
"6","(-3925,5200)","2","standard","I81";
;
CDS_LIB"standard"
ROOM"RISER1"
HDL_TAP"TRUE"
BODY_TYPE"PLUMBING"
BOM_COST"IO_SLOT";
"B \NAC \NWC"7;
"S \NAC"
BN"6"42;
%"TAP"
"6","(-3925,5300)","2","standard","I82";
;
CDS_LIB"standard"
ROOM"RISER1"
HDL_TAP"TRUE"
BODY_TYPE"PLUMBING"
BOM_COST"IO_SLOT";
"B \NAC \NWC"7;
"S \NAC"
BN"5"128;
%"TAP"
"6","(-3925,5400)","2","standard","I83";
;
CDS_LIB"standard"
ROOM"RISER1"
HDL_TAP"TRUE"
BODY_TYPE"PLUMBING"
BOM_COST"IO_SLOT";
"B \NAC \NWC"7;
"S \NAC"
BN"4"11;
%"TAP"
"6","(-3775,5250)","2","standard","I84";
;
CDS_LIB"standard"
ROOM"RISER1"
HDL_TAP"TRUE"
BODY_TYPE"PLUMBING"
BOM_COST"IO_SLOT";
"B \NAC \NWC"8;
"S \NAC"
BN"5"24;
%"TAP"
"6","(-3775,5350)","2","standard","I85";
;
CDS_LIB"standard"
ROOM"RISER1"
HDL_TAP"TRUE"
BODY_TYPE"PLUMBING"
BOM_COST"IO_SLOT";
"B \NAC \NWC"8;
"S \NAC"
BN"4"12;
%"TAP"
"6","(-3775,5450)","2","standard","I86";
;
CDS_LIB"standard"
ROOM"RISER1"
HDL_TAP"TRUE"
BODY_TYPE"PLUMBING"
BOM_COST"IO_SLOT";
"B \NAC \NWC"8;
"S \NAC"
BN"3"43;
%"TAP"
"6","(-3925,5500)","2","standard","I87";
;
CDS_LIB"standard"
ROOM"RISER1"
HDL_TAP"TRUE"
BODY_TYPE"PLUMBING"
BOM_COST"IO_SLOT";
"B \NAC \NWC"7;
"S \NAC"
BN"3"44;
%"TAP"
"6","(-3925,5700)","2","standard","I88";
;
CDS_LIB"standard"
ROOM"RISER1"
HDL_TAP"TRUE"
BODY_TYPE"PLUMBING"
BOM_COST"IO_SLOT";
"B \NAC \NWC"7;
"S \NAC"
BN"1"48;
%"TAP"
"6","(-3925,5600)","2","standard","I89";
;
CDS_LIB"standard"
ROOM"RISER1"
HDL_TAP"TRUE"
BODY_TYPE"PLUMBING"
BOM_COST"IO_SLOT";
"B \NAC \NWC"7;
"S \NAC"
BN"2"46;
%"TAP"
"6","(-5650,4500)","0","standard","I9";
;
CDS_LIB"standard"
BODY_TYPE"PLUMBING"
HDL_TAP"TRUE";
"B \NAC \NWC"2;
"S \NAC"
BN"13"124;
%"TAP"
"6","(-3775,5650)","2","standard","I90";
;
CDS_LIB"standard"
ROOM"RISER1"
HDL_TAP"TRUE"
BODY_TYPE"PLUMBING"
BOM_COST"IO_SLOT";
"B \NAC \NWC"8;
"S \NAC"
BN"1"47;
%"TAP"
"6","(-3775,5550)","2","standard","I91";
;
CDS_LIB"standard"
ROOM"RISER1"
HDL_TAP"TRUE"
BODY_TYPE"PLUMBING"
BOM_COST"IO_SLOT";
"B \NAC \NWC"8;
"S \NAC"
BN"2"45;
%"TAP"
"6","(-3925,5800)","2","standard","I92";
;
CDS_LIB"standard"
ROOM"RISER1"
HDL_TAP"TRUE"
BODY_TYPE"PLUMBING"
BOM_COST"IO_SLOT";
"B \NAC \NWC"7;
"S \NAC"
BN"0"130;
%"TAP"
"6","(-3775,5750)","2","standard","I93";
;
CDS_LIB"standard"
ROOM"RISER1"
HDL_TAP"TRUE"
BODY_TYPE"PLUMBING"
BOM_COST"IO_SLOT";
"B \NAC \NWC"8;
"S \NAC"
BN"0"129;
%"Q_CAP_DIFFBUS"
"2","(-4925,4850)","2","pure_quanta","I96";
;
LOCATION"C520"
$SEC"1"
CDS_SEC"1"
VALUE"DIFF BUS_0.22UF"
CDS_LMAN_SYM_OUTLINE"-25,50,25,-50"
CDS_LIB"pure_quanta"
VOLTAGE"6.3V"
TOLERANCE"20%"
PART_NUMBER"SP_CH4221MEE01"
MATERIAL"X6S"
PIN_NAMES_ROTATE"True"
PACK_TYPE"C0201";
"2"
$PN"2"121;
"1"
$PN"1"37;
%"TAP"
"6","(-5650,5000)","0","standard","I97";
;
CDS_LIB"standard"
BODY_TYPE"PLUMBING"
HDL_TAP"TRUE";
"B \NAC \NWC"2;
"S \NAC"
BN"8"16;
%"TAP"
"6","(-5650,5100)","0","standard","I98";
;
CDS_LIB"standard"
BODY_TYPE"PLUMBING"
HDL_TAP"TRUE";
"B \NAC \NWC"2;
"S \NAC"
BN"7"127;
%"TAP"
"6","(-5800,5250)","0","standard","I99";
;
CDS_LIB"standard"
BODY_TYPE"PLUMBING"
HDL_TAP"TRUE";
"B \NAC \NWC"3;
"S \NAC"
BN"5"9;
END.
